FILE_TYPE = CONNECTIVITY;
{Allegro Design Entry HDL 17.2-2016 S081 (4005846) 1/11/2022}
"PAGE_NUMBER" = 307;
0"NC";
1"P3V3_AUX\g"$PHYS_NET_NAME"P3V3_AUX"VOLTAGE"3.3"CDS_PHYS_NET_NAME"P3V3_AUX"$PHYS_NET_NAME"P3V3_AUX"VOLTAGE"3.3"CDS_PHYS_NET_NAME"P3V3_AUX";
2"P3V3_AUX\g";
3"P3V3_AUX\g"$PHYS_NET_NAME"P3V3_AUX"VOLTAGE"3.3"CDS_PHYS_NET_NAME"P3V3_AUX"$PHYS_NET_NAME"P3V3_AUX"VOLTAGE"3.3"CDS_PHYS_NET_NAME"P3V3_AUX";
4"GND\g"CDS_PHYS_NET_NAME"GND"VOLTAGE"0";
5"GND\g";
6"GND\g"CDS_PHYS_NET_NAME"GND"VOLTAGE"0";
7"GND\g";
8"GND\g";
9"GND\g";
10"GND\g"VOLTAGE"0";
11"GND\g";
12"OCP_V3_2_AUX_PWR_EN"CDS_PHYS_NET_NAME"OCP_V3_2_AUX_PWR_EN";
13"FB_BMC_ISOLATE_R2";
14"FB_BMC_ISOLATE1";
15"NCSI_BMC_TXD1_R1";
16"FM_NCSI_OCP_V3_2_R_OE";
17"OCP_V3_2_AUX_PWR_EN_R1"CDS_PHYS_NET_NAME"OCP_V3_2_AUX_PWR_EN_R1";
18"FM_OCP_V3_2_PWR_GOOD"CDS_PHYS_NET_NAME"FM_OCP_SFF_PWR_GOOD";
19"OCP_V3_2_RBT_ARB_IN";
20"OCP_V3_2_RBT_ARB_IN_R"CDS_PHYS_NET_NAME"OCP_SFF_RBT_ARB_IN";
21"NCSI_OCP_V3_2_TX_EN";
22"OCP_V3_2_RBT_ARB_OUT";
23"NCSI_BMC_RXD1_R1";
24"RMII_OCP_BMC_RXD_1";
25"NCSI_BMC_TXD0_R1";
26"NCSI_BMC_TX_EN_R1";
27"RMII_BMC_OCP_TXD_0";
28"RMII_BMC_OCP_TXD_1";
29"RMII_OCP_BMC_RXD_0";
30"NCSI_OCP_V3_2_TXD1";
31"NCSI_BMC_RXD0_R1"CDS_PHYS_NET_NAME"NCSI_BMC_RXD0_R";
32"NCSI_OCP_V3_2_RXD0"CDS_PHYS_NET_NAME"NCSI_OCP_SFF_RXD0";
33"RMII_BMC_OCP_TX_EN";
34"OCP_V3_2_ISO1_RBT_ARB_IN"CDS_PHYS_NET_NAME"OCP_SFF_ISO_RBT_ARB_IN";
35"NCSI_OCP_V3_2_CRS_DV"CDS_PHYS_NET_NAME"NCSI_OCP_SFF_CRS_DV";
36"NCSI_BMC_CRS_DV_R1"CDS_PHYS_NET_NAME"NCSI_BMC_CRS_DV_R";
37"NCSI_OCP_V3_2_RXD1";
38"OCP_V3_2_ISO2_RBT_ARB_OUT";
39"NCSI_OCP_V3_2_TXD0";
40"OCP_V3_2_ISO_BIF2_EN"CDS_PHYS_NET_NAME"OCP_SFF_ISO_BIF2_EN";
41"OCP_V3_2_ISO_BIF1_EN"CDS_PHYS_NET_NAME"OCP_SFF_ISO_BIF1_EN";
42"OCP_V3_2_ISO_BIF0_EN"CDS_PHYS_NET_NAME"OCP_SFF_ISO_BIF0_EN";
43"RMII_OCP_BMC_CRSDV";
%"Q_RES"
"1","(-75,-950)","0","pure_quanta","I12";
;
PART_NUMBER"CS00002JB13"
PACK_TYPE"0402LF"
VALUE"0"
MATERIAL"EMPTY"
TOLERANCE"5%"
WATTAGE"1/16W"
$LOCATION"R3206"
CDS_LIB"pure_quanta"
CDS_LOCATION"R3206"
$SEC"1"
CDS_SEC"1";
"B"
$PN"2"14;
"A"
$PN"1"16;
%"UNIVERSAL_GND"
"1","(350,-850)","0","logical_power","I14";
;
CDS_LIB"logical_power"
HDL_POWER"GND";
"A"11;
%"Q_RES"
"2","(350,-625)","0","pure_quanta","I15";
;
PART_NUMBER"CS41002FB09"
PACK_TYPE"0402LF"
WATTAGE"1/16W"
VALUE"100K"
TOLERANCE"1%"
MATERIAL"CHIP"
$LOCATION"R3207"
CDS_LIB"pure_quanta"
CDS_LOCATION"R3207"
$SEC"1"
CDS_SEC"1";
"A"
$PN"1"14;
"B"
$PN"2"11;
%"Q_CAP"
"1","(-1600,-25)","2","pure_quanta","I17";
;
PART_NUMBER"CH4104K1B00"
MATERIAL"X7R"
VOLTAGE"25V"
PACK_TYPE"0402"
TOLERANCE"10%"
VALUE"0.1UF"
$LOCATION"C1825"
CDS_LIB"pure_quanta"
CDS_LOCATION"C1825"
$SEC"1"
CDS_SEC"1";
"B"
$PN"2"8;
"A"
$PN"1"2;
%"UNIVERSAL_GND"
"1","(-1600,-250)","0","logical_power","I18";
;
HDL_POWER"GND"
CDS_LIB"logical_power";
"A"8;
%"UNIVERSAL_POWER"
"1","(-1600,250)","0","logical_power","I19";
;
HDL_POWER"P3V3_AUX"
CDS_LIB"logical_power";
"A"2;
%"UNIVERSAL_GND"
"1","(-325,425)","0","logical_power","I24";
;
CDS_LIB"logical_power"
HDL_POWER"GND";
"A"4;
%"UNIVERSAL_GND"
"1","(-525,1150)","0","logical_power","I25";
;
HDL_POWER"GND"
CDS_LIB"logical_power";
"A"5;
%"UNIVERSAL_POWER"
"1","(-325,1700)","0","logical_power","I26";
;
HDL_POWER"P3V3_AUX"
CDS_LIB"logical_power";
"A"3;
%"UNIVERSAL_GND"
"1","(-325,1850)","0","logical_power","I31";
;
HDL_POWER"GND"
CDS_LIB"logical_power";
"A"6;
%"74CBTLV3126PW"
"1","(225,2275)","2","pure_quanta","I32";
;
PART_NUMBER"AL003126K08"
VALUE"74CBTLV3126PW"
PART_TYPE"SMLF"
MATERIAL"IC"
$LOCATION"U222"
CDS_LIB"pure_quanta"
NEEDS_NO_SIZE"TRUE"
CDS_LMAN_SYM_OUTLINE"-250,350,250,-350"
CDS_LOCATION"U222"
$SEC"1"
CDS_SEC"1";
"VCC"
$PN"14"1;
"4OE"
$PN"13"14;
"4A"
$PN"12"20;
"4B"
$PN"11"34;
"3OE"
$PN"10"14;
"3A"
$PN"9"36;
"GND"
$PN"7"6;
"1A"
$PN"2"23;
"2B"
$PN"6"32;
"1B"
$PN"3"37;
"2OE"
$PN"4"14;
"1OE"
$PN"1"14;
"3B"
$PN"8"35;
"2A"
$PN"5"31;
%"Q_CAP"
"1","(-525,2800)","2","pure_quanta","I33";
;
PART_NUMBER"CH4104K1B00"
TOLERANCE"10%"
MATERIAL"X7R"
VOLTAGE"25V"
VALUE"0.1UF"
PACK_TYPE"0402"
$LOCATION"C1826"
CDS_LIB"pure_quanta"
CDS_LOCATION"C1826"
$SEC"1"
CDS_SEC"1";
"B"
$PN"2"7;
"A"
$PN"1"1;
%"UNIVERSAL_GND"
"1","(-525,2575)","0","logical_power","I34";
;
CDS_LIB"logical_power"
HDL_POWER"GND";
"A"7;
%"UNIVERSAL_POWER"
"1","(-325,3125)","0","logical_power","I35";
;
HDL_POWER"P3V3_AUX"
CDS_LIB"logical_power";
"A"1;
%"Q_RES"
"2","(1800,-2525)","0","pure_quanta","I37";
;
PART_NUMBER"CS11002FB07"
MATERIAL"CHIP"
PACK_TYPE"0402LF"
WATTAGE"1/16W"
TOLERANCE"1%"
VALUE"100"
$LOCATION"R3208"
CDS_LIB"pure_quanta"
CDS_LOCATION"R3208"
$SEC"1"
CDS_SEC"1";
"A"
$PN"1"42;
"B"
$PN"2"10;
%"Q_RES"
"2","(2050,-2525)","0","pure_quanta","I38";
;
PART_NUMBER"CS11002FB07"
PACK_TYPE"0402LF"
WATTAGE"1/16W"
TOLERANCE"1%"
VALUE"100"
MATERIAL"CHIP"
$LOCATION"R3216"
CDS_LIB"pure_quanta"
CDS_LOCATION"R3216"
$SEC"1"
CDS_SEC"1";
"A"
$PN"1"41;
"B"
$PN"2"10;
%"UNIVERSAL_GND"
"1","(1800,-2800)","0","logical_power","I39";
;
HDL_POWER"GND"
CDS_LIB"logical_power";
"A"10;
%"Q_RES"
"2","(2300,-2525)","0","pure_quanta","I40";
;
PART_NUMBER"CS11002FB07"
PACK_TYPE"0402LF"
WATTAGE"1/16W"
MATERIAL"CHIP"
VALUE"100"
TOLERANCE"1%"
$LOCATION"R3217"
CDS_LIB"pure_quanta"
CDS_LOCATION"R3217"
$SEC"1"
CDS_SEC"1";
"A"
$PN"1"40;
"B"
$PN"2"10;
%"Q_RES"
"1","(1900,600)","0","pure_quanta","I56";
;
PART_NUMBER"CS00002JB13"
VALUE"0"
MATERIAL"EMPTY"
$LOCATION"R3215"
CDS_LIB"pure_quanta"
PACK_TYPE"0402LF"
WATTAGE"1/16W"
TOLERANCE"5%"
CDS_LOCATION"R3215"
$SEC"1"
CDS_SEC"1";
"B"
$PN"2"28;
"A"
$PN"1"15;
%"Q_RES"
"1","(1900,750)","0","pure_quanta","I60";
;
PART_NUMBER"CS00002JB13"
MATERIAL"EMPTY"
VALUE"0"
$LOCATION"R3214"
CDS_LIB"pure_quanta"
PACK_TYPE"0402LF"
WATTAGE"1/16W"
TOLERANCE"5%"
CDS_LOCATION"R3214"
$SEC"1"
CDS_SEC"1";
"B"
$PN"2"27;
"A"
$PN"1"25;
%"Q_RES"
"1","(1900,900)","0","pure_quanta","I61";
;
PART_NUMBER"CS00002JB13"
MATERIAL"EMPTY"
VALUE"0"
$LOCATION"R3213"
CDS_LIB"pure_quanta"
TOLERANCE"5%"
PACK_TYPE"0402LF"
WATTAGE"1/16W"
CDS_LOCATION"R3213"
$SEC"1"
CDS_SEC"1";
"B"
$PN"2"33;
"A"
$PN"1"26;
%"Q_RES"
"1","(1900,2025)","0","pure_quanta","I62";
;
PART_NUMBER"CS02202FB02"
MATERIAL"EMPTY"
VALUE"22"
$LOCATION"R3212"
CDS_LIB"pure_quanta"
PACK_TYPE"0402LF"
TOLERANCE"1%"
WATTAGE"1/16W"
CDS_LOCATION"R3212"
$SEC"1"
CDS_SEC"1";
"B"
$PN"2"24;
"A"
$PN"1"23;
%"Q_RES"
"1","(1900,2175)","0","pure_quanta","I63";
;
PART_NUMBER"CS02202FB02"
MATERIAL"EMPTY"
VALUE"22"
$LOCATION"R3211"
CDS_LIB"pure_quanta"
PACK_TYPE"0402LF"
TOLERANCE"1%"
WATTAGE"1/16W"
CDS_LOCATION"R3211"
$SEC"1"
CDS_SEC"1";
"B"
$PN"2"29;
"A"
$PN"1"31;
%"Q_RES"
"1","(3450,2475)","0","pure_quanta","I64";
;
PART_NUMBER"CS02202FB02"
VALUE"22"
PACK_TYPE"0402LF"
MATERIAL"EMPTY"
WATTAGE"1/16W"
$LOCATION"R3209"
TOLERANCE"1%"
CDS_LIB"pure_quanta"
CDS_LOCATION"R3209"
$SEC"1"
CDS_SEC"1";
"B"
$PN"2"19;
"A"
$PN"1"20;
%"Q_RES"
"1","(1900,2325)","0","pure_quanta","I65";
;
PART_NUMBER"CS02202FB02"
MATERIAL"EMPTY"
VALUE"22"
$LOCATION"R3210"
WATTAGE"1/16W"
TOLERANCE"1%"
PACK_TYPE"0402LF"
CDS_LIB"pure_quanta"
CDS_LOCATION"R3210"
$SEC"1"
CDS_SEC"1";
"B"
$PN"2"43;
"A"
$PN"1"36;
%"Q_CAP"
"1","(-525,1375)","2","pure_quanta","I77";
;
PART_NUMBER"CH4104K1B00"
TOLERANCE"10%"
VOLTAGE"25V"
VALUE"0.1UF"
MATERIAL"X7R"
PACK_TYPE"0402"
$LOCATION"C1827"
CDS_LIB"pure_quanta"
CDS_LOCATION"C1827"
$SEC"1"
CDS_SEC"1";
"B"
$PN"2"5;
"A"
$PN"1"3;
%"74CBTLV3126PW"
"1","(225,850)","2","pure_quanta","I78";
;
PART_NUMBER"AL003126K08"
PART_TYPE"SMLF"
VALUE"74CBTLV3126PW"
MATERIAL"IC"
$LOCATION"U223"
CDS_LIB"pure_quanta"
NEEDS_NO_SIZE"TRUE"
CDS_LMAN_SYM_OUTLINE"-250,350,250,-350"
CDS_LOCATION"U223"
$SEC"1"
CDS_SEC"1";
"VCC"
$PN"14"3;
"4OE"
$PN"13"14;
"4A"
$PN"12"22;
"4B"
$PN"11"38;
"3OE"
$PN"10"14;
"3A"
$PN"9"26;
"GND"
$PN"7"4;
"1A"
$PN"2"15;
"2B"
$PN"6"39;
"1B"
$PN"3"30;
"2OE"
$PN"4"14;
"1OE"
$PN"1"14;
"3B"
$PN"8"21;
"2A"
$PN"5"25;
%"Q_RES"
"1","(3275,2275)","1","pure_quanta","I79";
;
PART_NUMBER"CS00002JB13"
VALUE"0"
MATERIAL"CHIP"
$LOCATION"R3244"
CDS_LIB"pure_quanta"
WATTAGE"1/16W"
PACK_TYPE"0402LF"
TOLERANCE"5%"
CDS_LOCATION"R3244"
$SEC"1"
CDS_SEC"1";
"B"
$PN"2"20;
"A"
$PN"1"22;
%"74LVC1G126SE7"
"1","(-1300,-425)","0","pure_quanta","I80";
;
PART_NUMBER"AL1G0126009"
MATERIAL"IC"
PART_TYPE"SMLF"
VALUE"74LVC1G126SE-7"
$LOCATION"U286"
NEEDS_NO_SIZE"TRUE"
CDS_LMAN_SYM_OUTLINE"-100,100,100,-100"
CDS_LIB"pure_quanta"
CDS_LOCATION"U286"
$SEC"1"
CDS_SEC"1";
"OE"
$PN"1"17;
"GND"
$PN"3"9;
"VCC"
$PN"5"2;
"Y"
$PN"4"13;
"A"
$PN"2"18;
%"Q_RES"
"1","(-2875,-475)","0","pure_quanta","I81";
;
PART_NUMBER"CS03322FB03"
PACK_TYPE"0402LF"
TOLERANCE"1%"
VALUE"33.2"
WATTAGE"1/16W"
MATERIAL"CHIP"
$LOCATION"R3203"
CDS_LIB"pure_quanta"
CDS_LOCATION"R3203"
$SEC"1"
CDS_SEC"1";
"B"
$PN"2"17;
"A"
$PN"1"12;
%"UNIVERSAL_GND"
"1","(-1300,-800)","0","logical_power","I83";
;
CDS_LIB"logical_power"
HDL_POWER"GND";
"A"9;
%"Q_RES"
"1","(-75,-425)","0","pure_quanta","I85";
;
PART_NUMBER"CS04992FB07"
MATERIAL"CHIP"
VALUE"49.9"
LOCATION"R3205"
CDS_LIB"pure_quanta"
PACK_TYPE"0402LF"
TOLERANCE"1%"
WATTAGE"1/16W"
$SEC"1"
CDS_SEC"1";
"B"
$PN"2"14;
"A"
$PN"1"13;
END.
